(kicad_pcb
	(version 20260206)
	(generator "pcbnew")
	(generator_version "10.0")
	(general
		(thickness 1.6)
		(legacy_teardrops no)
	)
	(paper "A4")
	(title_block
		(title "01162023_DA0F0TEBIF0_F0T_Expander_BD_F_brd_V02_OCP.brd")
		(comment 1 "Grand Teton / footprints 5660-5665 of 9728")
	)
	(layers
		(0 "F.Cu" signal "TOP")
		(4 "In1.Cu" signal "GND")
		(6 "In2.Cu" signal "VCC")
		(8 "In3.Cu" signal "VCC1")
		(10 "In4.Cu" signal "GND1")
		(12 "In5.Cu" signal "IN1")
		(14 "In6.Cu" signal "GND2")
		(16 "In7.Cu" signal "IN2")
		(18 "In8.Cu" signal "GND3")
		(20 "In9.Cu" signal "IN3")
		(22 "In10.Cu" signal "GND4")
		(24 "In11.Cu" signal "IN4")
		(26 "In12.Cu" signal "GND5")
		(28 "In13.Cu" signal "IN5")
		(30 "In14.Cu" signal "GND6")
		(32 "In15.Cu" signal "IN6")
		(34 "In16.Cu" signal "GND7")
		(2 "B.Cu" signal "BOTTOM")
		(9 "F.Adhes" user "F.Adhesive")
		(11 "B.Adhes" user "B.Adhesive")
		(13 "F.Paste" user "Package Geometry/Pastemask Top")
		(15 "B.Paste" user "Package Geometry/Pastemask Bottom")
		(5 "F.SilkS" user "Ref Des/Silkscreen Top")
		(7 "B.SilkS" user "Ref Des/Silkscreen Bottom")
		(1 "F.Mask" user "Board Geometry/Soldermask Top")
		(3 "B.Mask" user "Board Geometry/Soldermask Bottom")
		(17 "Dwgs.User" user "User.Drawings")
		(19 "Cmts.User" user "User.Comments")
		(21 "Eco1.User" user "User.Eco1")
		(23 "Eco2.User" user "User.Eco2")
		(25 "Edge.Cuts" user "Board Geometry/Outline")
		(27 "Margin" user)
		(31 "F.CrtYd" user "Package Geometry/Place Bound Top")
		(29 "B.CrtYd" user "Package Geometry/Place Bound Bottom")
		(35 "F.Fab" user "Ref Des/Assembly Top")
		(33 "B.Fab" user "Ref Des/Assembly Bottom")
	)
	(footprint ""
		(layer "F.Cu")
		(at 223.967294 -453.501252)
		(property "Reference" "X70"
			(at -0.1778 -1.92913 0)
			(unlocked yes)
			(layer "F.SilkS")
			(effects
				(font
					(size 0.7874 0.5842)
					(thickness 0.1524)
				)
				(justify left)
			)
		)
		(property "Value" ""
			(at 0 0 0)
			(layer "F.Fab")
			(effects
				(font
					(size 1.27 1.27)
				)
			)
		)
		(property "Device Type" "TP_TDR_4P_FTS_MPKT4_H025P0200_IO_TP15_TP_TDR_4P_DIP"
			(at 1.30175 1.27 90)
			(unlocked yes)
			(layer "F.Fab")
			(hide yes)
			(effects
				(font
					(size 0.635 0.4064)
					(thickness 0.1524)
				)
			)
		)
		(property "User Part Number" "TP15"
			(at 1.30175 1.27 90)
			(unlocked yes)
			(layer "Cmts.User")
			(hide yes)
			(effects
				(font
					(size 0.635 0.4064)
					(thickness 0.1524)
				)
			)
		)
		(duplicate_pad_numbers_are_jumpers no)
		(fp_line
			(start 0 -1.27)
			(end 0 -0.635)
			(stroke
				(width 0.1524)
				(type default)
			)
			(layer "F.SilkS")
		)
		(fp_line
			(start 0 0.635)
			(end 0 1.905)
			(stroke
				(width 0.1524)
				(type default)
			)
			(layer "F.SilkS")
		)
		(fp_line
			(start 0 3.175)
			(end 0 3.81)
			(stroke
				(width 0.1524)
				(type default)
			)
			(layer "F.SilkS")
		)
		(fp_line
			(start 0 3.81)
			(end 2.54 3.81)
			(stroke
				(width 0.1524)
				(type default)
			)
			(layer "F.SilkS")
		)
		(fp_line
			(start 2.54 -1.27)
			(end 0 -1.27)
			(stroke
				(width 0.1524)
				(type default)
			)
			(layer "F.SilkS")
		)
		(fp_line
			(start 2.54 -1.1303)
			(end 2.54 -1.27)
			(stroke
				(width 0.1524)
				(type default)
			)
			(layer "F.SilkS")
		)
		(fp_line
			(start 2.54 1.4097)
			(end 2.54 1.1303)
			(stroke
				(width 0.1524)
				(type default)
			)
			(layer "F.SilkS")
		)
		(fp_line
			(start 2.54 3.81)
			(end 2.54 3.6703)
			(stroke
				(width 0.1524)
				(type default)
			)
			(layer "F.SilkS")
		)
		(fp_poly
			(pts
				(xy -0.761746 0) (xy -2.285746 -0.762) (xy -2.285746 0.762)
			)
			(stroke
				(width 0)
				(type default)
			)
			(fill yes)
			(layer "F.SilkS")
		)
		(fp_line
			(start 0 -1.27)
			(end 0 3.81)
			(stroke
				(width 0.1)
				(type default)
			)
			(layer "F.Fab")
		)
		(fp_line
			(start 0 3.81)
			(end 2.54 3.81)
			(stroke
				(width 0.1)
				(type default)
			)
			(layer "F.Fab")
		)
		(fp_line
			(start 2.54 -1.27)
			(end 0 -1.27)
			(stroke
				(width 0.1)
				(type default)
			)
			(layer "F.Fab")
		)
		(fp_line
			(start 2.54 3.81)
			(end 2.54 -1.27)
			(stroke
				(width 0.1)
				(type default)
			)
			(layer "F.Fab")
		)
		(fp_poly
			(pts
				(xy -0.761746 0) (xy -2.285746 -0.762) (xy -2.285746 0.762)
			)
			(stroke
				(width 0)
				(type default)
			)
			(fill yes)
			(layer "F.Fab")
		)
		(pad "1" thru_hole circle
			(at 0 0)
			(size 1.0033 1.0033)
			(drill 0.249936)
			(layers "*.Cu" "*.Mask")
			(remove_unused_layers no)
			(net "TDR_DIFF_100_IN2_DIP")
			(clearance 0.10795)
			(thermal_gap 0.10795)
			(padstack
				(mode front_inner_back)
				(layer "Inner"
					(shape circle)
					(size 0.8001 0.8001)
					(clearance 0.1524)
				)
				(layer "B.Cu"
					(shape circle)
					(size 1.0033 1.0033)
					(clearance 0.10795)
				)
			)
		)
		(pad "2" thru_hole circle
			(at 2.54 0)
			(size 1.9939 1.9939)
			(drill 0.249936)
			(layers "*.Cu" "*.Mask")
			(remove_unused_layers no)
			(net "COUPON_GND1")
			(clearance 0.10795)
			(thermal_gap 0.10795)
			(padstack
				(mode front_inner_back)
				(layer "Inner"
					(shape circle)
					(size 0.8001 0.8001)
					(clearance 0.1524)
				)
				(layer "B.Cu"
					(shape circle)
					(size 1.9939 1.9939)
					(clearance 0.10795)
				)
			)
		)
		(pad "3" thru_hole circle
			(at 2.54 2.54)
			(size 1.9939 1.9939)
			(drill 0.249936)
			(layers "*.Cu" "*.Mask")
			(remove_unused_layers no)
			(net "COUPON_GND1")
			(clearance 0.10795)
			(thermal_gap 0.10795)
			(padstack
				(mode front_inner_back)
				(layer "Inner"
					(shape circle)
					(size 0.8001 0.8001)
					(clearance 0.1524)
				)
				(layer "B.Cu"
					(shape circle)
					(size 1.9939 1.9939)
					(clearance 0.10795)
				)
			)
		)
		(pad "4" thru_hole circle
			(at 0 2.54)
			(size 1.0033 1.0033)
			(drill 0.249936)
			(layers "*.Cu" "*.Mask")
			(remove_unused_layers no)
			(net "TDR_DIFF_100_IN2_DIN")
			(clearance 0.10795)
			(thermal_gap 0.10795)
			(padstack
				(mode front_inner_back)
				(layer "Inner"
					(shape circle)
					(size 0.8001 0.8001)
					(clearance 0.1524)
				)
				(layer "B.Cu"
					(shape circle)
					(size 1.0033 1.0033)
					(clearance 0.10795)
				)
			)
		)
	)
	(footprint ""
		(layer "F.Cu")
		(at 349.762318 -205.231492 90)
		(property "Reference" "R6421"
			(at 0 0 90)
			(layer "F.SilkS")
			(hide yes)
			(effects
				(font
					(size 1.27 1.27)
				)
			)
		)
		(property "Value" ""
			(at 0 0 90)
			(layer "F.Fab")
			(effects
				(font
					(size 1.27 1.27)
				)
			)
		)
		(duplicate_pad_numbers_are_jumpers no)
		(fp_line
			(start 0.7874 -0.4064)
			(end 0.7874 0.4064)
			(stroke
				(width 0.1524)
				(type default)
			)
			(layer "F.SilkS")
		)
		(fp_line
			(start -0.7874 -0.4064)
			(end 0.7874 -0.4064)
			(stroke
				(width 0.1524)
				(type default)
			)
			(layer "F.SilkS")
		)
		(fp_line
			(start 0.7874 0.4064)
			(end -0.7874 0.4064)
			(stroke
				(width 0.1524)
				(type default)
			)
			(layer "F.SilkS")
		)
		(fp_line
			(start -0.7874 0.4064)
			(end -0.7874 -0.4064)
			(stroke
				(width 0.1524)
				(type default)
			)
			(layer "F.SilkS")
		)
		(fp_line
			(start -0.12065 -0.305054)
			(end -0.12065 -0.2794)
			(stroke
				(width 0.1)
				(type default)
			)
			(layer "F.Fab")
		)
		(fp_line
			(start -0.67945 -0.305054)
			(end -0.12065 -0.305054)
			(stroke
				(width 0.1)
				(type default)
			)
			(layer "F.Fab")
		)
		(fp_line
			(start 0.67945 -0.3048)
			(end 0.67945 0.3048)
			(stroke
				(width 0.1)
				(type default)
			)
			(layer "F.Fab")
		)
		(fp_line
			(start 0.12065 -0.3048)
			(end 0.67945 -0.3048)
			(stroke
				(width 0.1)
				(type default)
			)
			(layer "F.Fab")
		)
		(fp_line
			(start 0.12065 -0.2794)
			(end 0.12065 -0.3048)
			(stroke
				(width 0.1)
				(type default)
			)
			(layer "F.Fab")
		)
		(fp_line
			(start -0.12065 -0.2794)
			(end 0.12065 -0.2794)
			(stroke
				(width 0.1)
				(type default)
			)
			(layer "F.Fab")
		)
		(fp_line
			(start 0.120396 0.2794)
			(end -0.12065 0.2794)
			(stroke
				(width 0.1)
				(type default)
			)
			(layer "F.Fab")
		)
		(fp_line
			(start -0.12065 0.2794)
			(end -0.12065 0.3048)
			(stroke
				(width 0.1)
				(type default)
			)
			(layer "F.Fab")
		)
		(fp_line
			(start 0.67945 0.3048)
			(end 0.120396 0.3048)
			(stroke
				(width 0.1)
				(type default)
			)
			(layer "F.Fab")
		)
		(fp_line
			(start 0.120396 0.3048)
			(end 0.120396 0.2794)
			(stroke
				(width 0.1)
				(type default)
			)
			(layer "F.Fab")
		)
		(fp_line
			(start -0.12065 0.3048)
			(end -0.67945 0.3048)
			(stroke
				(width 0.1)
				(type default)
			)
			(layer "F.Fab")
		)
		(fp_line
			(start -0.67945 0.3048)
			(end -0.67945 -0.305054)
			(stroke
				(width 0.1)
				(type default)
			)
			(layer "F.Fab")
		)
		(pad "1" smd circle
			(at -0.40005 0 90)
			(size 0 0)
			(layers "F.Cu" "F.Mask" "F.Paste")
			(net "FPGA_PEX2_MODE_SEL1_R")
		)
		(pad "2" smd circle
			(at 0.40005 0 90)
			(size 0 0)
			(layers "F.Cu" "F.Mask" "F.Paste")
			(net "FPGA_PEX2_MODE_SEL1")
		)
	)
	(footprint ""
		(layer "F.Cu")
		(at 314.165234 -435.658006 -90)
		(property "Reference" "J53"
			(at -2.4257 -5.635752 90)
			(unlocked yes)
			(layer "F.SilkS")
			(effects
				(font
					(size 0.7874 0.5842)
					(thickness 0.1524)
				)
			)
		)
		(property "Value" ""
			(at 0 0 270)
			(layer "F.Fab")
			(effects
				(font
					(size 1.27 1.27)
				)
			)
		)
		(duplicate_pad_numbers_are_jumpers no)
		(fp_line
			(start 0 4.011168)
			(end -3.330702 -4.771136)
			(stroke
				(width 0.1524)
				(type default)
			)
			(layer "F.SilkS")
		)
		(fp_line
			(start -3.330702 -4.771136)
			(end 3.330702 -4.771136)
			(stroke
				(width 0.1524)
				(type default)
			)
			(layer "F.SilkS")
		)
		(fp_line
			(start 3.330702 -4.771136)
			(end 0 4.011168)
			(stroke
				(width 0.1524)
				(type default)
			)
			(layer "F.SilkS")
		)
		(fp_line
			(start 0 4.011168)
			(end -3.330702 -4.771136)
			(stroke
				(width 0.1)
				(type default)
			)
			(layer "F.Fab")
		)
		(fp_line
			(start -3.330702 -4.771136)
			(end 3.330702 -4.771136)
			(stroke
				(width 0.1)
				(type default)
			)
			(layer "F.Fab")
		)
		(fp_line
			(start 3.330702 -4.771136)
			(end 0 4.011168)
			(stroke
				(width 0.1)
				(type default)
			)
			(layer "F.Fab")
		)
		(pad "1" thru_hole circle
			(at 0 0 270)
			(size 2.159 2.159)
			(drill 1.7018)
			(layers "*.Cu" "*.Mask")
			(remove_unused_layers no)
			(net "COUPON_GND1")
			(clearance 0.0254)
			(thermal_gap 0.0254)
		)
		(pad "2" thru_hole circle
			(at -1.27 -3.348736 270)
			(size 2.159 2.159)
			(drill 1.7018)
			(layers "*.Cu" "*.Mask")
			(remove_unused_layers no)
			(net "TDR_SE_50_OHM_BOT")
			(clearance 0.0254)
			(thermal_gap 0.0254)
		)
		(pad "3" thru_hole circle
			(at 1.27 -3.348736 270)
			(size 2.159 2.159)
			(drill 1.7018)
			(layers "*.Cu" "*.Mask")
			(remove_unused_layers no)
			(net "TDR_SE_50_OHM_BOT")
			(clearance 0.0254)
			(thermal_gap 0.0254)
		)
	)
	(footprint ""
		(layer "F.Cu")
		(at 357.246682 -205.160118 90)
		(property "Reference" "R6420"
			(at 0 0 90)
			(layer "F.SilkS")
			(hide yes)
			(effects
				(font
					(size 1.27 1.27)
				)
			)
		)
		(property "Value" ""
			(at 0 0 90)
			(layer "F.Fab")
			(effects
				(font
					(size 1.27 1.27)
				)
			)
		)
		(duplicate_pad_numbers_are_jumpers no)
		(fp_line
			(start 0.7874 -0.4064)
			(end 0.7874 0.4064)
			(stroke
				(width 0.1524)
				(type default)
			)
			(layer "F.SilkS")
		)
		(fp_line
			(start -0.7874 -0.4064)
			(end 0.7874 -0.4064)
			(stroke
				(width 0.1524)
				(type default)
			)
			(layer "F.SilkS")
		)
		(fp_line
			(start 0.7874 0.4064)
			(end -0.7874 0.4064)
			(stroke
				(width 0.1524)
				(type default)
			)
			(layer "F.SilkS")
		)
		(fp_line
			(start -0.7874 0.4064)
			(end -0.7874 -0.4064)
			(stroke
				(width 0.1524)
				(type default)
			)
			(layer "F.SilkS")
		)
		(fp_line
			(start -0.12065 -0.305054)
			(end -0.12065 -0.2794)
			(stroke
				(width 0.1)
				(type default)
			)
			(layer "F.Fab")
		)
		(fp_line
			(start -0.67945 -0.305054)
			(end -0.12065 -0.305054)
			(stroke
				(width 0.1)
				(type default)
			)
			(layer "F.Fab")
		)
		(fp_line
			(start 0.67945 -0.3048)
			(end 0.67945 0.3048)
			(stroke
				(width 0.1)
				(type default)
			)
			(layer "F.Fab")
		)
		(fp_line
			(start 0.12065 -0.3048)
			(end 0.67945 -0.3048)
			(stroke
				(width 0.1)
				(type default)
			)
			(layer "F.Fab")
		)
		(fp_line
			(start 0.12065 -0.2794)
			(end 0.12065 -0.3048)
			(stroke
				(width 0.1)
				(type default)
			)
			(layer "F.Fab")
		)
		(fp_line
			(start -0.12065 -0.2794)
			(end 0.12065 -0.2794)
			(stroke
				(width 0.1)
				(type default)
			)
			(layer "F.Fab")
		)
		(fp_line
			(start 0.120396 0.2794)
			(end -0.12065 0.2794)
			(stroke
				(width 0.1)
				(type default)
			)
			(layer "F.Fab")
		)
		(fp_line
			(start -0.12065 0.2794)
			(end -0.12065 0.3048)
			(stroke
				(width 0.1)
				(type default)
			)
			(layer "F.Fab")
		)
		(fp_line
			(start 0.67945 0.3048)
			(end 0.120396 0.3048)
			(stroke
				(width 0.1)
				(type default)
			)
			(layer "F.Fab")
		)
		(fp_line
			(start 0.120396 0.3048)
			(end 0.120396 0.2794)
			(stroke
				(width 0.1)
				(type default)
			)
			(layer "F.Fab")
		)
		(fp_line
			(start -0.12065 0.3048)
			(end -0.67945 0.3048)
			(stroke
				(width 0.1)
				(type default)
			)
			(layer "F.Fab")
		)
		(fp_line
			(start -0.67945 0.3048)
			(end -0.67945 -0.305054)
			(stroke
				(width 0.1)
				(type default)
			)
			(layer "F.Fab")
		)
		(pad "1" smd circle
			(at -0.40005 0 90)
			(size 0 0)
			(layers "F.Cu" "F.Mask" "F.Paste")
			(net "FPGA_PEX2_MODE_SEL2_R")
		)
		(pad "2" smd circle
			(at 0.40005 0 90)
			(size 0 0)
			(layers "F.Cu" "F.Mask" "F.Paste")
			(net "FPGA_PEX2_MODE_SEL2")
		)
	)
	(footprint ""
		(layer "F.Cu")
		(at 232.46969 -83.318858 90)
		(property "Reference" "R1013"
			(at 0 0 90)
			(layer "F.SilkS")
			(hide yes)
			(effects
				(font
					(size 1.27 1.27)
				)
			)
		)
		(property "Value" ""
			(at 0 0 90)
			(layer "F.Fab")
			(effects
				(font
					(size 1.27 1.27)
				)
			)
		)
		(duplicate_pad_numbers_are_jumpers no)
		(fp_line
			(start -0.7874 -0.4064)
			(end 0.7874 -0.4064)
			(stroke
				(width 0.1524)
				(type default)
			)
			(layer "F.SilkS")
		)
		(fp_line
			(start 0.7874 0.4064)
			(end 0.009652 0.4064)
			(stroke
				(width 0.1524)
				(type default)
			)
			(layer "F.SilkS")
		)
		(fp_line
			(start -0.7874 0.4064)
			(end -0.7874 -0.4064)
			(stroke
				(width 0.1524)
				(type default)
			)
			(layer "F.SilkS")
		)
		(fp_line
			(start -0.12065 -0.305054)
			(end -0.12065 -0.2794)
			(stroke
				(width 0.1)
				(type default)
			)
			(layer "F.Fab")
		)
		(fp_line
			(start -0.67945 -0.305054)
			(end -0.12065 -0.305054)
			(stroke
				(width 0.1)
				(type default)
			)
			(layer "F.Fab")
		)
		(fp_line
			(start 0.67945 -0.3048)
			(end 0.67945 0.3048)
			(stroke
				(width 0.1)
				(type default)
			)
			(layer "F.Fab")
		)
		(fp_line
			(start 0.12065 -0.3048)
			(end 0.67945 -0.3048)
			(stroke
				(width 0.1)
				(type default)
			)
			(layer "F.Fab")
		)
		(fp_line
			(start 0.12065 -0.2794)
			(end 0.12065 -0.3048)
			(stroke
				(width 0.1)
				(type default)
			)
			(layer "F.Fab")
		)
		(fp_line
			(start -0.12065 -0.2794)
			(end 0.12065 -0.2794)
			(stroke
				(width 0.1)
				(type default)
			)
			(layer "F.Fab")
		)
		(fp_line
			(start 0.120396 0.2794)
			(end -0.12065 0.2794)
			(stroke
				(width 0.1)
				(type default)
			)
			(layer "F.Fab")
		)
		(fp_line
			(start -0.12065 0.2794)
			(end -0.12065 0.3048)
			(stroke
				(width 0.1)
				(type default)
			)
			(layer "F.Fab")
		)
		(fp_line
			(start 0.67945 0.3048)
			(end 0.120396 0.3048)
			(stroke
				(width 0.1)
				(type default)
			)
			(layer "F.Fab")
		)
		(fp_line
			(start 0.120396 0.3048)
			(end 0.120396 0.2794)
			(stroke
				(width 0.1)
				(type default)
			)
			(layer "F.Fab")
		)
		(fp_line
			(start -0.12065 0.3048)
			(end -0.67945 0.3048)
			(stroke
				(width 0.1)
				(type default)
			)
			(layer "F.Fab")
		)
		(fp_line
			(start -0.67945 0.3048)
			(end -0.67945 -0.305054)
			(stroke
				(width 0.1)
				(type default)
			)
			(layer "F.Fab")
		)
		(pad "1" smd rect
			(at -0.40005 0 270)
			(size 0.4572 0.508)
			(layers "F.Cu" "F.Mask" "F.Paste")
			(net "USB2_FT4232_SDB_R_DN")
		)
		(pad "2" smd rect
			(at 0.40005 0 270)
			(size 0.4572 0.508)
			(layers "F.Cu" "F.Mask" "F.Paste")
			(net "USB2_FT4232_SDB_DN")
		)
	)
	(footprint ""
		(layer "F.Cu")
		(at 95.4786 -199.7456)
		(property "Reference" "R6625"
			(at 0 0 0)
			(layer "F.SilkS")
			(hide yes)
			(effects
				(font
					(size 1.27 1.27)
				)
			)
		)
		(property "Value" ""
			(at 0 0 0)
			(layer "F.Fab")
			(effects
				(font
					(size 1.27 1.27)
				)
			)
		)
		(duplicate_pad_numbers_are_jumpers no)
		(fp_line
			(start -0.7874 -0.4064)
			(end 0.7874 -0.4064)
			(stroke
				(width 0.1524)
				(type default)
			)
			(layer "F.SilkS")
		)
		(fp_line
			(start -0.7874 0.4064)
			(end -0.7874 -0.4064)
			(stroke
				(width 0.1524)
				(type default)
			)
			(layer "F.SilkS")
		)
		(fp_line
			(start 0.7874 -0.4064)
			(end 0.7874 0.4064)
			(stroke
				(width 0.1524)
				(type default)
			)
			(layer "F.SilkS")
		)
		(fp_line
			(start 0.7874 0.4064)
			(end -0.7874 0.4064)
			(stroke
				(width 0.1524)
				(type default)
			)
			(layer "F.SilkS")
		)
		(fp_line
			(start -0.67945 -0.305054)
			(end -0.12065 -0.305054)
			(stroke
				(width 0.1)
				(type default)
			)
			(layer "F.Fab")
		)
		(fp_line
			(start -0.67945 0.3048)
			(end -0.67945 -0.305054)
			(stroke
				(width 0.1)
				(type default)
			)
			(layer "F.Fab")
		)
		(fp_line
			(start -0.12065 -0.305054)
			(end -0.12065 -0.2794)
			(stroke
				(width 0.1)
				(type default)
			)
			(layer "F.Fab")
		)
		(fp_line
			(start -0.12065 -0.2794)
			(end 0.12065 -0.2794)
			(stroke
				(width 0.1)
				(type default)
			)
			(layer "F.Fab")
		)
		(fp_line
			(start -0.12065 0.2794)
			(end -0.12065 0.3048)
			(stroke
				(width 0.1)
				(type default)
			)
			(layer "F.Fab")
		)
		(fp_line
			(start -0.12065 0.3048)
			(end -0.67945 0.3048)
			(stroke
				(width 0.1)
				(type default)
			)
			(layer "F.Fab")
		)
		(fp_line
			(start 0.120396 0.2794)
			(end -0.12065 0.2794)
			(stroke
				(width 0.1)
				(type default)
			)
			(layer "F.Fab")
		)
		(fp_line
			(start 0.120396 0.3048)
			(end 0.120396 0.2794)
			(stroke
				(width 0.1)
				(type default)
			)
			(layer "F.Fab")
		)
		(fp_line
			(start 0.12065 -0.3048)
			(end 0.67945 -0.3048)
			(stroke
				(width 0.1)
				(type default)
			)
			(layer "F.Fab")
		)
		(fp_line
			(start 0.12065 -0.2794)
			(end 0.12065 -0.3048)
			(stroke
				(width 0.1)
				(type default)
			)
			(layer "F.Fab")
		)
		(fp_line
			(start 0.67945 -0.3048)
			(end 0.67945 0.3048)
			(stroke
				(width 0.1)
				(type default)
			)
			(layer "F.Fab")
		)
		(fp_line
			(start 0.67945 0.3048)
			(end 0.120396 0.3048)
			(stroke
				(width 0.1)
				(type default)
			)
			(layer "F.Fab")
		)
		(pad "1" smd circle
			(at -0.40005 0)
			(size 0 0)
			(layers "F.Cu" "F.Mask" "F.Paste")
			(net "UART_PEX3_CLI_BUF_R_TX")
		)
		(pad "2" smd circle
			(at 0.40005 0)
			(size 0 0)
			(layers "F.Cu" "F.Mask" "F.Paste")
			(net "UART_PEX3_CLI_CP2108_TX")
		)
	)
)
